# T6G (Grand Teton) — schematic netlist excerpt (pin names and nets, part order shuffled) for the footprints in the layout excerpt that follows; sources: Cadence DE-HDL packaged netlist, KiCad conversion of 04192023_DAF0TMB3IC0_F0TG_MB_C_brd_V02_OCP.brd

C2648  Q_CAP  22UF 4V 20% X6S  pkg C0402  page 70 : A = PVDD11_S3_P0 ; B = GND
R1267  Q_RES  4.7K 1% EMPTY  pkg 0402LF  page 258 : A = P3V3_ADC128_2_VCC ; B = ADC128_2_VREF

(kicad_pcb
	(version 20260206)
	(generator "pcbnew")
	(generator_version "10.0")
	(general
		(thickness 1.6)
		(legacy_teardrops no)
	)
	(paper "A4")
	(title_block
		(title "04192023_DAF0TMB3IC0_F0TG_MB_C_brd_V02_OCP.brd")
		(comment 1 "Grand Teton / footprints 6850-6851 of 8354")
	)
	(layers
		(0 "F.Cu" signal "TOP")
		(4 "In1.Cu" signal "GND")
		(6 "In2.Cu" signal "IN1")
		(8 "In3.Cu" signal "GND1")
		(10 "In4.Cu" signal "IN2")
		(12 "In5.Cu" signal "GND2")
		(14 "In6.Cu" signal "IN3")
		(16 "In7.Cu" signal "GND3")
		(18 "In8.Cu" signal "VCC")
		(20 "In9.Cu" signal "VCC1")
		(22 "In10.Cu" signal "GND4")
		(24 "In11.Cu" signal "IN4")
		(26 "In12.Cu" signal "GND5")
		(28 "In13.Cu" signal "IN5")
		(30 "In14.Cu" signal "GND6")
		(32 "In15.Cu" signal "IN6")
		(34 "In16.Cu" signal "GND7")
		(2 "B.Cu" signal "BOTTOM")
		(9 "F.Adhes" user "F.Adhesive")
		(11 "B.Adhes" user "B.Adhesive")
		(13 "F.Paste" user "Package Geometry/Pastemask Top")
		(15 "B.Paste" user "Package Geometry/Pastemask Bottom")
		(5 "F.SilkS" user "Ref Des/Silkscreen Top")
		(7 "B.SilkS" user "Ref Des/Silkscreen Bottom")
		(1 "F.Mask" user "Board Geometry/Soldermask Top")
		(3 "B.Mask" user "Board Geometry/Soldermask Bottom")
		(17 "Dwgs.User" user "User.Drawings")
		(19 "Cmts.User" user "User.Comments")
		(21 "Eco1.User" user "User.Eco1")
		(23 "Eco2.User" user "User.Eco2")
		(25 "Edge.Cuts" user "Board Geometry/Outline")
		(27 "Margin" user)
		(31 "F.CrtYd" user "Package Geometry/Place Bound Top")
		(29 "B.CrtYd" user "Package Geometry/Place Bound Bottom")
		(35 "F.Fab" user "Ref Des/Assembly Top")
		(33 "B.Fab" user "Ref Des/Assembly Bottom")
	)
	(footprint ""
		(layer "B.Cu")
		(at 216.127076 -327.009252)
		(property "Reference" "R1267"
			(at 0 0 0)
			(layer "B.SilkS")
			(hide yes)
			(effects
				(font
					(size 1.27 1.27)
				)
				(justify mirror)
			)
		)
		(property "Value" ""
			(at 0 0 0)
			(layer "B.Fab")
			(effects
				(font
					(size 1.27 1.27)
				)
				(justify mirror)
			)
		)
		(duplicate_pad_numbers_are_jumpers no)
		(fp_line
			(start -0.7874 -0.4064)
			(end -0.7874 0.4064)
			(stroke
				(width 0.1524)
				(type default)
			)
			(layer "B.SilkS")
		)
		(fp_line
			(start -0.7874 0.4064)
			(end 0.7874 0.4064)
			(stroke
				(width 0.1524)
				(type default)
			)
			(layer "B.SilkS")
		)
		(fp_line
			(start 0.7874 -0.4064)
			(end -0.7874 -0.4064)
			(stroke
				(width 0.1524)
				(type default)
			)
			(layer "B.SilkS")
		)
		(fp_line
			(start 0.7874 0.4064)
			(end 0.7874 -0.4064)
			(stroke
				(width 0.1524)
				(type default)
			)
			(layer "B.SilkS")
		)
		(fp_line
			(start -0.67945 -0.3048)
			(end -0.67945 0.3048)
			(stroke
				(width 0.1)
				(type default)
			)
			(layer "B.Fab")
		)
		(fp_line
			(start -0.67945 0.3048)
			(end -0.120396 0.3048)
			(stroke
				(width 0.1)
				(type default)
			)
			(layer "B.Fab")
		)
		(fp_line
			(start -0.12065 -0.3048)
			(end -0.67945 -0.3048)
			(stroke
				(width 0.1)
				(type default)
			)
			(layer "B.Fab")
		)
		(fp_line
			(start -0.12065 -0.2794)
			(end -0.12065 -0.3048)
			(stroke
				(width 0.1)
				(type default)
			)
			(layer "B.Fab")
		)
		(fp_line
			(start -0.120396 0.2794)
			(end 0.12065 0.2794)
			(stroke
				(width 0.1)
				(type default)
			)
			(layer "B.Fab")
		)
		(fp_line
			(start -0.120396 0.3048)
			(end -0.120396 0.2794)
			(stroke
				(width 0.1)
				(type default)
			)
			(layer "B.Fab")
		)
		(fp_line
			(start 0.12065 -0.305054)
			(end 0.12065 -0.2794)
			(stroke
				(width 0.1)
				(type default)
			)
			(layer "B.Fab")
		)
		(fp_line
			(start 0.12065 -0.2794)
			(end -0.12065 -0.2794)
			(stroke
				(width 0.1)
				(type default)
			)
			(layer "B.Fab")
		)
		(fp_line
			(start 0.12065 0.2794)
			(end 0.12065 0.3048)
			(stroke
				(width 0.1)
				(type default)
			)
			(layer "B.Fab")
		)
		(fp_line
			(start 0.12065 0.3048)
			(end 0.67945 0.3048)
			(stroke
				(width 0.1)
				(type default)
			)
			(layer "B.Fab")
		)
		(fp_line
			(start 0.67945 -0.305054)
			(end 0.12065 -0.305054)
			(stroke
				(width 0.1)
				(type default)
			)
			(layer "B.Fab")
		)
		(fp_line
			(start 0.67945 0.3048)
			(end 0.67945 -0.305054)
			(stroke
				(width 0.1)
				(type default)
			)
			(layer "B.Fab")
		)
		(pad "1" smd circle
			(at 0.40005 0 180)
			(size 0 0)
			(layers "B.Cu" "B.Mask" "B.Paste")
			(net "P3V3_ADC128_2_VCC")
		)
		(pad "2" smd circle
			(at -0.40005 0 180)
			(size 0 0)
			(layers "B.Cu" "B.Mask" "B.Paste")
			(net "ADC128_2_VREF")
		)
	)
	(footprint ""
		(layer "B.Cu")
		(at 359.994454 -263.84631)
		(property "Reference" "C2648"
			(at 0 0 0)
			(layer "B.SilkS")
			(hide yes)
			(effects
				(font
					(size 1.27 1.27)
				)
				(justify mirror)
			)
		)
		(property "Value" ""
			(at 0 0 0)
			(layer "B.Fab")
			(effects
				(font
					(size 1.27 1.27)
				)
				(justify mirror)
			)
		)
		(duplicate_pad_numbers_are_jumpers no)
		(fp_line
			(start -0.7874 -0.4064)
			(end -0.7874 0.4064)
			(stroke
				(width 0.1524)
				(type default)
			)
			(layer "B.SilkS")
		)
		(fp_line
			(start -0.7874 0.4064)
			(end 0.7874 0.4064)
			(stroke
				(width 0.1524)
				(type default)
			)
			(layer "B.SilkS")
		)
		(fp_line
			(start 0.7874 -0.4064)
			(end -0.7874 -0.4064)
			(stroke
				(width 0.1524)
				(type default)
			)
			(layer "B.SilkS")
		)
		(fp_line
			(start 0.7874 0.4064)
			(end 0.7874 -0.4064)
			(stroke
				(width 0.1524)
				(type default)
			)
			(layer "B.SilkS")
		)
		(fp_line
			(start -0.67945 -0.3048)
			(end -0.67945 0.3048)
			(stroke
				(width 0.1)
				(type default)
			)
			(layer "B.Fab")
		)
		(fp_line
			(start -0.67945 0.3048)
			(end -0.120396 0.3048)
			(stroke
				(width 0.1)
				(type default)
			)
			(layer "B.Fab")
		)
		(fp_line
			(start -0.12065 -0.3048)
			(end -0.67945 -0.3048)
			(stroke
				(width 0.1)
				(type default)
			)
			(layer "B.Fab")
		)
		(fp_line
			(start -0.12065 -0.2794)
			(end -0.12065 -0.3048)
			(stroke
				(width 0.1)
				(type default)
			)
			(layer "B.Fab")
		)
		(fp_line
			(start -0.120396 0.2794)
			(end 0.12065 0.2794)
			(stroke
				(width 0.1)
				(type default)
			)
			(layer "B.Fab")
		)
		(fp_line
			(start -0.120396 0.3048)
			(end -0.120396 0.2794)
			(stroke
				(width 0.1)
				(type default)
			)
			(layer "B.Fab")
		)
		(fp_line
			(start 0.12065 -0.305054)
			(end 0.12065 -0.2794)
			(stroke
				(width 0.1)
				(type default)
			)
			(layer "B.Fab")
		)
		(fp_line
			(start 0.12065 -0.2794)
			(end -0.12065 -0.2794)
			(stroke
				(width 0.1)
				(type default)
			)
			(layer "B.Fab")
		)
		(fp_line
			(start 0.12065 0.2794)
			(end 0.12065 0.3048)
			(stroke
				(width 0.1)
				(type default)
			)
			(layer "B.Fab")
		)
		(fp_line
			(start 0.12065 0.3048)
			(end 0.67945 0.3048)
			(stroke
				(width 0.1)
				(type default)
			)
			(layer "B.Fab")
		)
		(fp_line
			(start 0.67945 -0.305054)
			(end 0.12065 -0.305054)
			(stroke
				(width 0.1)
				(type default)
			)
			(layer "B.Fab")
		)
		(fp_line
			(start 0.67945 0.3048)
			(end 0.67945 -0.305054)
			(stroke
				(width 0.1)
				(type default)
			)
			(layer "B.Fab")
		)
		(pad "1" smd circle
			(at 0.40005 0 180)
			(size 0 0)
			(layers "B.Cu" "B.Mask" "B.Paste")
			(net "PVDD11_S3_P0")
		)
		(pad "2" smd circle
			(at -0.40005 0 180)
			(size 0 0)
			(layers "B.Cu" "B.Mask" "B.Paste")
			(net "GND")
		)
	)
)
